(kicad_pcb
	(version 20241229)
	(generator "pcbnew")
	(generator_version "9.0")
	(general
		(thickness 1.552)
		(legacy_teardrops no)
	)
	(paper "A4")
	(title_block
		(date "2023-07-25")
		(rev "1.1.4")
		(comment 9 "footprints 258-261 of 379")
	)
	(layers
		(0 "F.Cu" signal)
		(4 "In1.Cu" signal)
		(6 "In2.Cu" signal)
		(8 "In3.Cu" signal)
		(10 "In4.Cu" signal)
		(12 "In5.Cu" signal)
		(14 "In6.Cu" signal)
		(2 "B.Cu" signal)
		(9 "F.Adhes" user "F.Adhesive")
		(11 "B.Adhes" user "B.Adhesive")
		(13 "F.Paste" user)
		(15 "B.Paste" user)
		(5 "F.SilkS" user "F.Silkscreen")
		(7 "B.SilkS" user "B.Silkscreen")
		(1 "F.Mask" user)
		(3 "B.Mask" user)
		(17 "Dwgs.User" user "User.Drawings")
		(19 "Cmts.User" user "User.Comments")
		(21 "Eco1.User" user "User.Eco1")
		(23 "Eco2.User" user "User.Eco2")
		(25 "Edge.Cuts" user)
		(27 "Margin" user)
		(31 "F.CrtYd" user "F.Courtyard")
		(29 "B.CrtYd" user "B.Courtyard")
		(35 "F.Fab" user)
		(33 "B.Fab" user)
	)
	(footprint "antmicro-footprints:TSSOP-14_4.4x5mm_P0.65mm"
		(layer "B.Cu")
		(at 157.53 103.35 180)
		(descr "TSSOP, 14 Pin (JEDEC MO-153 Var AB-1 https://www.jedec.org/document_search?search_api_views_fulltext=MO-153), generated with kicad-footprint-generator ipc_gullwing_generator.py")
		(tags "TSSOP SO")
		(property "Reference" "U2"
			(at -0.9 -3.29 0)
			(layer "B.SilkS")
			(effects
				(font
					(size 0.65 0.65)
					(thickness 0.15)
				)
				(justify left mirror)
			)
		)
		(property "Value" "LM339_TSSOP_Split"
			(at -3.8 -4.3 0)
			(layer "B.Fab")
			(hide yes)
			(effects
				(font
					(size 0.7 0.7)
					(thickness 0.15)
				)
				(justify left bottom mirror)
			)
		)
		(property "Datasheet" "https://www.ti.com/lit/ds/symlink/lm339b.pdf?ts=1679641364820&ref_url=https%253A%252F%252Fwww.google.com%252F"
			(at 0 0 180)
			(layer "F.Fab")
			(hide yes)
			(effects
				(font
					(size 1.27 1.27)
					(thickness 0.15)
				)
			)
		)
		(property "Description" "Analogue Comparator, Differential, 4 Comparators, 300 ns, 2V to 36V, TSSOP, 14 Pins"
			(at 0 0 180)
			(layer "F.Fab")
			(hide yes)
			(effects
				(font
					(size 1.27 1.27)
					(thickness 0.15)
				)
			)
		)
		(property "Author" "Antmicro"
			(at 315.06 206.7 0)
			(layer "B.Fab")
			(hide yes)
			(effects
				(font
					(size 1 1)
					(thickness 0.15)
				)
				(justify mirror)
			)
		)
		(property "License" "Apache-2.0"
			(at 315.06 206.7 0)
			(layer "B.Fab")
			(hide yes)
			(effects
				(font
					(size 1 1)
					(thickness 0.15)
				)
				(justify mirror)
			)
		)
		(property "MPN" "LM339PW"
			(at 315.06 206.7 0)
			(layer "B.Fab")
			(hide yes)
			(effects
				(font
					(size 1 1)
					(thickness 0.15)
				)
				(justify mirror)
			)
		)
		(property "Manufacturer" "Texas Instruments"
			(at 315.06 206.7 0)
			(layer "B.Fab")
			(hide yes)
			(effects
				(font
					(size 1 1)
					(thickness 0.15)
				)
				(justify mirror)
			)
		)
		(sheetname "/Power Supply/")
		(sheetfile "supply.kicad_sch")
		(attr smd)
		(fp_line
			(start 2.3 2.3)
			(end 2.3 2.605)
			(stroke
				(width 0.15)
				(type solid)
			)
			(layer "B.SilkS")
		)
		(fp_line
			(start 2.3 -2.3)
			(end 2.3 -2.6)
			(stroke
				(width 0.15)
				(type solid)
			)
			(layer "B.SilkS")
		)
		(fp_line
			(start 2.3 -2.6)
			(end -2.3 -2.6)
			(stroke
				(width 0.15)
				(type solid)
			)
			(layer "B.SilkS")
		)
		(fp_line
			(start -2.3 2.61)
			(end 2.3 2.605)
			(stroke
				(width 0.15)
				(type solid)
			)
			(layer "B.SilkS")
		)
		(fp_line
			(start -2.3 2.61)
			(end -2.3 2.3)
			(stroke
				(width 0.15)
				(type solid)
			)
			(layer "B.SilkS")
		)
		(fp_line
			(start -2.3 -2.6)
			(end -2.3 -2.3)
			(stroke
				(width 0.15)
				(type solid)
			)
			(layer "B.SilkS")
		)
		(fp_line
			(start -2.9 2.3)
			(end -2.3 2.3)
			(stroke
				(width 0.15)
				(type solid)
			)
			(layer "B.SilkS")
		)
		(fp_line
			(start 3.7 2.6)
			(end -3.7 2.6)
			(stroke
				(width 0.05)
				(type solid)
			)
			(layer "B.CrtYd")
		)
		(fp_line
			(start 3.7 -2.6)
			(end 3.7 2.6)
			(stroke
				(width 0.05)
				(type solid)
			)
			(layer "B.CrtYd")
		)
		(fp_line
			(start -3.7 2.6)
			(end -3.7 -2.6)
			(stroke
				(width 0.05)
				(type solid)
			)
			(layer "B.CrtYd")
		)
		(fp_line
			(start -3.7 -2.6)
			(end 3.7 -2.6)
			(stroke
				(width 0.05)
				(type solid)
			)
			(layer "B.CrtYd")
		)
		(fp_line
			(start 2.2 2.5)
			(end 2.2 -2.499)
			(stroke
				(width 0.15)
				(type solid)
			)
			(layer "B.Fab")
		)
		(fp_line
			(start 2.2 -2.499)
			(end -2.202 -2.499)
			(stroke
				(width 0.15)
				(type solid)
			)
			(layer "B.Fab")
		)
		(fp_line
			(start -1.2 2.5)
			(end 2.2 2.5)
			(stroke
				(width 0.15)
				(type solid)
			)
			(layer "B.Fab")
		)
		(fp_line
			(start -2.202 1.5)
			(end -1.2 2.5)
			(stroke
				(width 0.15)
				(type solid)
			)
			(layer "B.Fab")
		)
		(fp_line
			(start -2.202 -2.499)
			(end -2.202 1.5)
			(stroke
				(width 0.15)
				(type solid)
			)
			(layer "B.Fab")
		)
		(fp_text user "."
			(at -3.7 2.8 0)
			(layer "B.SilkS")
			(effects
				(font
					(size 1 1)
					(thickness 0.15)
				)
				(justify left mirror)
			)
		)
		(pad "1" smd roundrect
			(at -2.863 1.95 180)
			(size 1.475 0.4)
			(layers "B.Cu" "B.Mask" "B.Paste")
			(roundrect_rratio 0.25)
			(net 58 "Net-(D1-A)")
			(pintype "output")
		)
		(pad "2" smd roundrect
			(at -2.863 1.301 180)
			(size 1.475 0.4)
			(layers "B.Cu" "B.Mask" "B.Paste")
			(roundrect_rratio 0.25)
			(net 58 "Net-(D1-A)")
			(pintype "output")
		)
		(pad "3" smd roundrect
			(at -2.863 0.652 180)
			(size 1.475 0.4)
			(layers "B.Cu" "B.Mask" "B.Paste")
			(roundrect_rratio 0.25)
			(net 14 "+5V")
			(pinfunction "V+")
			(pintype "power_in")
		)
		(pad "4" smd roundrect
			(at -2.863 0 180)
			(size 1.475 0.4)
			(layers "B.Cu" "B.Mask" "B.Paste")
			(roundrect_rratio 0.25)
			(net 141 "/Power Supply/VREF_0V45")
			(pintype "input")
		)
		(pad "5" smd roundrect
			(at -2.863 -0.65 180)
			(size 1.475 0.4)
			(layers "B.Cu" "B.Mask" "B.Paste")
			(roundrect_rratio 0.25)
			(net 2 "+3V3")
			(pintype "input")
		)
		(pad "6" smd roundrect
			(at -2.863 -1.3 180)
			(size 1.475 0.4)
			(layers "B.Cu" "B.Mask" "B.Paste")
			(roundrect_rratio 0.25)
			(net 141 "/Power Supply/VREF_0V45")
			(pintype "input")
		)
		(pad "7" smd roundrect
			(at -2.863 -1.949 180)
			(size 1.475 0.4)
			(layers "B.Cu" "B.Mask" "B.Paste")
			(roundrect_rratio 0.25)
			(net 4 "1V0_Power")
			(pintype "input")
		)
		(pad "8" smd roundrect
			(at 2.862 -1.949 180)
			(size 1.475 0.4)
			(layers "B.Cu" "B.Mask" "B.Paste")
			(roundrect_rratio 0.25)
			(net 141 "/Power Supply/VREF_0V45")
			(pintype "input")
		)
		(pad "9" smd roundrect
			(at 2.862 -1.3 180)
			(size 1.475 0.4)
			(layers "B.Cu" "B.Mask" "B.Paste")
			(roundrect_rratio 0.25)
			(net 49 "1V0_Clean")
			(pintype "input")
		)
		(pad "10" smd roundrect
			(at 2.862 -0.65 180)
			(size 1.475 0.4)
			(layers "B.Cu" "B.Mask" "B.Paste")
			(roundrect_rratio 0.25)
			(net 141 "/Power Supply/VREF_0V45")
			(pintype "input")
		)
		(pad "11" smd roundrect
			(at 2.862 0 180)
			(size 1.475 0.4)
			(layers "B.Cu" "B.Mask" "B.Paste")
			(roundrect_rratio 0.25)
			(net 50 "+1V8")
			(pintype "input")
		)
		(pad "12" smd roundrect
			(at 2.862 0.652 180)
			(size 1.475 0.4)
			(layers "B.Cu" "B.Mask" "B.Paste")
			(roundrect_rratio 0.25)
			(net 1 "GND")
			(pinfunction "V-")
			(pintype "power_in")
		)
		(pad "13" smd roundrect
			(at 2.862 1.301 180)
			(size 1.475 0.4)
			(layers "B.Cu" "B.Mask" "B.Paste")
			(roundrect_rratio 0.25)
			(net 58 "Net-(D1-A)")
			(pintype "output")
		)
		(pad "14" smd roundrect
			(at 2.862 1.95 180)
			(size 1.475 0.4)
			(layers "B.Cu" "B.Mask" "B.Paste")
			(roundrect_rratio 0.25)
			(net 58 "Net-(D1-A)")
			(pintype "output")
		)
	)
	(footprint "antmicro-footprints:C_0402_1005Metric"
		(layer "B.Cu")
		(at 97.1 71.7 -90)
		(descr "Capacitor SMD 0402")
		(tags "capacitor SMD 0402")
		(property "Reference" "C69"
			(at -0.96 0.67 90)
			(layer "B.SilkS")
			(effects
				(font
					(size 0.65 0.65)
					(thickness 0.15)
				)
				(justify left bottom mirror)
			)
		)
		(property "Value" "C_100n_0402"
			(at 0 -1.4 90)
			(layer "B.Fab")
			(hide yes)
			(effects
				(font
					(size 0.7 0.7)
					(thickness 0.15)
				)
				(justify left bottom mirror)
			)
		)
		(property "Datasheet" "https://www.murata.com/products/productdetail?partno=GRM155R61H104KE14%23"
			(at 0 0 270)
			(layer "F.Fab")
			(hide yes)
			(effects
				(font
					(size 1.27 1.27)
					(thickness 0.15)
				)
			)
		)
		(property "Description" "SMD Multilayer Ceramic Capacitor, 0.1 µF, 50 V, 0402 [1005 Metric], ± 10%, X5R, GRM Series"
			(at 0 0 270)
			(layer "F.Fab")
			(hide yes)
			(effects
				(font
					(size 1.27 1.27)
					(thickness 0.15)
				)
			)
		)
		(property "Author" "Antmicro"
			(at 25.4 168.8 0)
			(layer "B.Fab")
			(hide yes)
			(effects
				(font
					(size 1 1)
					(thickness 0.15)
				)
				(justify mirror)
			)
		)
		(property "Dielectric" "X5R"
			(at 25.4 168.8 0)
			(layer "B.Fab")
			(hide yes)
			(effects
				(font
					(size 1 1)
					(thickness 0.15)
				)
				(justify mirror)
			)
		)
		(property "License" "Apache-2.0"
			(at 25.4 168.8 0)
			(layer "B.Fab")
			(hide yes)
			(effects
				(font
					(size 1 1)
					(thickness 0.15)
				)
				(justify mirror)
			)
		)
		(property "MPN" "GRM155R61H104KE14D"
			(at 25.4 168.8 0)
			(layer "B.Fab")
			(hide yes)
			(effects
				(font
					(size 1 1)
					(thickness 0.15)
				)
				(justify mirror)
			)
		)
		(property "Manufacturer" "Murata"
			(at 25.4 168.8 0)
			(layer "B.Fab")
			(hide yes)
			(effects
				(font
					(size 1 1)
					(thickness 0.15)
				)
				(justify mirror)
			)
		)
		(property "Val" "100n"
			(at 25.4 168.8 0)
			(layer "B.Fab")
			(hide yes)
			(effects
				(font
					(size 1 1)
					(thickness 0.15)
				)
				(justify mirror)
			)
		)
		(property "Voltage" "50V"
			(at 25.4 168.8 0)
			(layer "B.Fab")
			(hide yes)
			(effects
				(font
					(size 1 1)
					(thickness 0.15)
				)
				(justify mirror)
			)
		)
		(sheetname "/SDI/")
		(sheetfile "sdi.kicad_sch")
		(attr smd)
		(fp_rect
			(start -0.925 0.47)
			(end 0.925 -0.47)
			(stroke
				(width 0.05)
				(type default)
			)
			(fill no)
			(layer "B.CrtYd")
		)
		(fp_line
			(start -0.494 0.25)
			(end 0.504 0.25)
			(stroke
				(width 0.15)
				(type solid)
			)
			(layer "B.Fab")
		)
		(fp_line
			(start 0.504 0.25)
			(end 0.504 -0.248)
			(stroke
				(width 0.15)
				(type solid)
			)
			(layer "B.Fab")
		)
		(fp_line
			(start -0.494 -0.248)
			(end -0.494 0.25)
			(stroke
				(width 0.15)
				(type solid)
			)
			(layer "B.Fab")
		)
		(fp_line
			(start 0.504 -0.248)
			(end -0.494 -0.248)
			(stroke
				(width 0.15)
				(type solid)
			)
			(layer "B.Fab")
		)
		(fp_text user "${REFERENCE}"
			(at -0.939 -4.599 90)
			(layer "B.Fab")
			(effects
				(font
					(size 0.7 0.7)
					(thickness 0.15)
				)
				(justify left bottom mirror)
			)
		)
		(fp_text user "Author: Antmicro"
			(at -0.939 -3.399 90)
			(layer "B.Fab")
			(effects
				(font
					(size 0.7 0.7)
					(thickness 0.15)
				)
				(justify left bottom mirror)
			)
		)
		(fp_text user "License: Apache-2.0"
			(at -0.939 -5.799 90)
			(layer "B.Fab")
			(effects
				(font
					(size 0.7 0.7)
					(thickness 0.15)
				)
				(justify left bottom mirror)
			)
		)
		(pad "1" smd roundrect
			(at -0.48 0 270)
			(size 0.59 0.64)
			(layers "B.Cu" "B.Mask" "B.Paste")
			(roundrect_rratio 0.25)
			(net 1 "GND")
			(pintype "passive")
		)
		(pad "2" smd roundrect
			(at 0.48 0 270)
			(size 0.59 0.64)
			(layers "B.Cu" "B.Mask" "B.Paste")
			(roundrect_rratio 0.25)
			(net 2 "+3V3")
			(pintype "passive")
		)
	)
	(footprint "antmicro-footprints:FB_0603_1608Metric"
		(layer "B.Cu")
		(at 129.94 99.63)
		(property "Reference" "FB3"
			(at 3.34 0.51 180)
			(layer "B.SilkS")
			(effects
				(font
					(size 0.65 0.65)
					(thickness 0.15)
				)
				(justify left bottom mirror)
			)
		)
		(property "Value" "FB_120Z_2A_0603"
			(at 0 -1.5 180)
			(layer "B.Fab")
			(hide yes)
			(effects
				(font
					(size 0.7 0.7)
					(thickness 0.15)
				)
				(justify left bottom mirror)
			)
		)
		(property "Datasheet" "https://www.murata.com/en-us/products/productdata/8796738650142/ENFA0003.pdf"
			(at 0 0 0)
			(layer "F.Fab")
			(hide yes)
			(effects
				(font
					(size 1.27 1.27)
					(thickness 0.15)
				)
			)
		)
		(property "Description" "Ferrite Bead, 0603 [1608 Metric], 120 ohm, 2 A, BLM18P, 0.05 ohm, ± 25%, DC power line"
			(at 0 0 0)
			(layer "F.Fab")
			(hide yes)
			(effects
				(font
					(size 1.27 1.27)
					(thickness 0.15)
				)
			)
		)
		(property "Author" "Antmicro"
			(at 0 0 0)
			(layer "B.Fab")
			(hide yes)
			(effects
				(font
					(size 1 1)
					(thickness 0.15)
				)
				(justify mirror)
			)
		)
		(property "License" "Apache-2.0"
			(at 0 0 0)
			(layer "B.Fab")
			(hide yes)
			(effects
				(font
					(size 1 1)
					(thickness 0.15)
				)
				(justify mirror)
			)
		)
		(property "MPN" "BLM18PG121SN1D"
			(at 0 0 0)
			(layer "B.Fab")
			(hide yes)
			(effects
				(font
					(size 1 1)
					(thickness 0.15)
				)
				(justify mirror)
			)
		)
		(property "Manufacturer" "Murata"
			(at 0 0 0)
			(layer "B.Fab")
			(hide yes)
			(effects
				(font
					(size 1 1)
					(thickness 0.15)
				)
				(justify mirror)
			)
		)
		(property "Val" "120Z/2A"
			(at 0 0 0)
			(unlocked yes)
			(layer "B.Fab")
			(hide yes)
			(effects
				(font
					(size 1 1)
					(thickness 0.15)
				)
				(justify mirror)
			)
		)
		(property "Current" ""
			(at 0 0 0)
			(unlocked yes)
			(layer "B.Fab")
			(hide yes)
			(effects
				(font
					(size 1 1)
					(thickness 0.15)
				)
				(justify mirror)
			)
		)
		(sheetname "/FPGA Power/")
		(sheetfile "FPGA_Power.kicad_sch")
		(attr smd)
		(fp_line
			(start -0.15 -0.4)
			(end 0.15 -0.4)
			(stroke
				(width 0.15)
				(type solid)
			)
			(layer "B.SilkS")
		)
		(fp_line
			(start -0.15 0.4)
			(end 0.15 0.4)
			(stroke
				(width 0.15)
				(type solid)
			)
			(layer "B.SilkS")
		)
		(fp_rect
			(start -1.25 0.65)
			(end 1.25 -0.65)
			(stroke
				(width 0.05)
				(type solid)
			)
			(fill no)
			(layer "B.CrtYd")
		)
		(fp_line
			(start -0.803 -0.406)
			(end -0.803 0.408)
			(stroke
				(width 0.15)
				(type solid)
			)
			(layer "B.Fab")
		)
		(fp_line
			(start 0.8 -0.406)
			(end -0.803 -0.406)
			(stroke
				(width 0.15)
				(type solid)
			)
			(layer "B.Fab")
		)
		(fp_line
			(start 0.8 0.408)
			(end -0.803 0.408)
			(stroke
				(width 0.15)
				(type solid)
			)
			(layer "B.Fab")
		)
		(fp_line
			(start 0.8 0.408)
			(end 0.8 -0.406)
			(stroke
				(width 0.15)
				(type solid)
			)
			(layer "B.Fab")
		)
		(fp_text user "${REFERENCE}"
			(at -1.653 -4.6 180)
			(layer "B.Fab")
			(effects
				(font
					(size 0.7 0.7)
					(thickness 0.15)
				)
				(justify left bottom mirror)
			)
		)
		(fp_text user "Author: Antmicro"
			(at -1.653 -3.162 180)
			(layer "B.Fab")
			(effects
				(font
					(size 0.7 0.7)
					(thickness 0.15)
				)
				(justify left bottom mirror)
			)
		)
		(fp_text user "License: Apache-2.0"
			(at -1.653 -5.9 180)
			(layer "B.Fab")
			(effects
				(font
					(size 0.7 0.7)
					(thickness 0.15)
				)
				(justify left bottom mirror)
			)
		)
		(pad "1" smd roundrect
			(at -0.7 0)
			(size 0.8 1)
			(layers "B.Cu" "B.Mask" "B.Paste")
			(roundrect_rratio 0.2)
			(net 11 "/FPGA Power/VCC_DPHY")
			(pintype "passive")
		)
		(pad "2" smd roundrect
			(at 0.7 0)
			(size 0.8 1)
			(layers "B.Cu" "B.Mask" "B.Paste")
			(roundrect_rratio 0.2)
			(net 49 "1V0_Clean")
			(pintype "passive")
		)
	)
	(footprint "antmicro-footprints:TP_SMD_0.75mm"
		(layer "B.Cu")
		(at 100.69 88.95 90)
		(property "Reference" "TP28"
			(at -0.59 0.34 90)
			(layer "B.SilkS")
			(effects
				(font
					(size 0.65 0.65)
					(thickness 0.15)
				)
				(justify left bottom mirror)
			)
		)
		(property "Value" "TP_0.75mm_SMD"
			(at 0 -1.2 90)
			(layer "B.Fab")
			(hide yes)
			(effects
				(font
					(size 0.7 0.7)
					(thickness 0.15)
				)
				(justify right bottom mirror)
			)
		)
		(property "Description" "SMT test point"
			(at 0 0 90)
			(layer "F.Fab")
			(hide yes)
			(effects
				(font
					(size 1.27 1.27)
					(thickness 0.15)
				)
			)
		)
		(property "Author" "Antmicro"
			(at 189.64 -11.74 0)
			(layer "B.Fab")
			(hide yes)
			(effects
				(font
					(size 1 1)
					(thickness 0.15)
				)
				(justify mirror)
			)
		)
		(property "License" "Apache-2.0"
			(at 189.64 -11.74 0)
			(layer "B.Fab")
			(hide yes)
			(effects
				(font
					(size 1 1)
					(thickness 0.15)
				)
				(justify mirror)
			)
		)
		(property "MPN" ""
			(at 189.64 -11.74 0)
			(layer "B.Fab")
			(hide yes)
			(effects
				(font
					(size 1 1)
					(thickness 0.15)
				)
				(justify mirror)
			)
		)
		(property "Manufacturer" ""
			(at 189.64 -11.74 0)
			(layer "B.Fab")
			(hide yes)
			(effects
				(font
					(size 1 1)
					(thickness 0.15)
				)
				(justify mirror)
			)
		)
		(sheetname "/SDI/")
		(sheetfile "sdi.kicad_sch")
		(attr exclude_from_pos_files)
		(fp_circle
			(center 0 0)
			(end 0.475 0)
			(stroke
				(width 0.05)
				(type default)
			)
			(fill no)
			(layer "B.CrtYd")
		)
		(fp_text user "License: Apache-2.0"
			(at -0.4 -5.101 270)
			(layer "B.Fab")
			(effects
				(font
					(size 0.7 0.7)
					(thickness 0.15)
				)
				(justify left bottom mirror)
			)
		)
		(fp_text user "${REFERENCE}"
			(at -0.4 -2.7 270)
			(layer "B.Fab")
			(effects
				(font
					(size 0.7 0.7)
					(thickness 0.15)
				)
				(justify left bottom mirror)
			)
		)
		(fp_text user "Author: Antmicro"
			(at -0.4 -3.901 270)
			(layer "B.Fab")
			(effects
				(font
					(size 0.7 0.7)
					(thickness 0.15)
				)
				(justify left bottom mirror)
			)
		)
		(pad "1" smd circle
			(at 0 0 90)
			(size 0.75 0.75)
			(layers "B.Cu" "B.Mask")
			(net 193 "/SDI/DVB_ASI")
			(pinfunction "1")
			(pintype "passive")
		)
	)
)
